(kicad_pcb
	(version 20260206)
	(generator "pcbnew")
	(generator_version "10.0")
	(general
		(thickness 1.6)
		(legacy_teardrops no)
	)
	(paper "A4")
	(title_block
		(title "03242023_DA0F0TMBIJ0_F0T_Motherboard_J_brd_V01_OCP.brd")
		(comment 1 "Grand Teton / footprint 37 of 6105 (J7), pads 225-291 of 291")
	)
	(layers
		(0 "F.Cu" signal "TOP")
		(4 "In1.Cu" signal "GND")
		(6 "In2.Cu" signal "IN1")
		(8 "In3.Cu" signal "GND1")
		(10 "In4.Cu" signal "IN2")
		(12 "In5.Cu" signal "GND2")
		(14 "In6.Cu" signal "IN3")
		(16 "In7.Cu" signal "GND3")
		(18 "In8.Cu" signal "VCC")
		(20 "In9.Cu" signal "VCC1")
		(22 "In10.Cu" signal "GND4")
		(24 "In11.Cu" signal "IN4")
		(26 "In12.Cu" signal "GND5")
		(28 "In13.Cu" signal "IN5")
		(30 "In14.Cu" signal "GND6")
		(32 "In15.Cu" signal "IN6")
		(34 "In16.Cu" signal "GND7")
		(2 "B.Cu" signal "BOTTOM")
		(9 "F.Adhes" user "F.Adhesive")
		(11 "B.Adhes" user "B.Adhesive")
		(13 "F.Paste" user "Package Geometry/Pastemask Top")
		(15 "B.Paste" user "Package Geometry/Pastemask Bottom")
		(5 "F.SilkS" user "Ref Des/Silkscreen Top")
		(7 "B.SilkS" user "Ref Des/Silkscreen Bottom")
		(1 "F.Mask" user "Board Geometry/Soldermask Top")
		(3 "B.Mask" user "Board Geometry/Soldermask Bottom")
		(17 "Dwgs.User" user "User.Drawings")
		(19 "Cmts.User" user "User.Comments")
		(21 "Eco1.User" user "User.Eco1")
		(23 "Eco2.User" user "User.Eco2")
		(25 "Edge.Cuts" user "Board Geometry/Outline")
		(27 "Margin" user)
		(31 "F.CrtYd" user "Package Geometry/Place Bound Top")
		(29 "B.CrtYd" user "Package Geometry/Place Bound Bottom")
		(35 "F.Fab" user "Ref Des/Assembly Top")
		(33 "B.Fab" user "Ref Des/Assembly Bottom")
	)
	(footprint ""
		(layer "F.Cu")
		(at 258.130548 -258.091686)
		(property "Reference" "J7"
			(at -3.683 -81.702148 0)
			(unlocked yes)
			(layer "F.SilkS")
			(effects
				(font
					(size 0.7874 0.5842)
					(thickness 0.1524)
				)
				(justify left)
			)
		)
		(property "Value" ""
			(at 0 0 0)
			(layer "F.Fab")
			(effects
				(font
					(size 1.27 1.27)
				)
			)
		)
		(duplicate_pad_numbers_are_jumpers no)
		(pad "225" smd rect
			(at 2.050034 9.774936 270)
			(size 0.519938 1.4986)
			(layers "F.Cu" "F.Mask" "F.Paste")
			(net "M_D_CPU0_SB_CA<5>")
		)
		(pad "226" smd rect
			(at 2.050034 10.625074 270)
			(size 0.519938 1.4986)
			(layers "F.Cu" "F.Mask" "F.Paste")
			(net "GND")
		)
		(pad "227" smd rect
			(at 2.050034 11.474958 270)
			(size 0.519938 1.4986)
			(layers "F.Cu" "F.Mask" "F.Paste")
			(net "M_D_CPU0_SB_PAR")
		)
		(pad "228" smd rect
			(at 2.050034 12.325096 270)
			(size 0.519938 1.4986)
			(layers "F.Cu" "F.Mask" "F.Paste")
			(net "GND")
		)
		(pad "229" smd rect
			(at 2.050034 13.17498 270)
			(size 0.519938 1.4986)
			(layers "F.Cu" "F.Mask" "F.Paste")
			(net "M_D_CPU0_SB_CS_N<1>")
		)
		(pad "230" smd rect
			(at 2.050034 14.025118 270)
			(size 0.519938 1.4986)
			(layers "F.Cu" "F.Mask" "F.Paste")
			(net "GND")
		)
		(pad "231" smd rect
			(at 2.050034 14.875002 270)
			(size 0.519938 1.4986)
			(layers "F.Cu" "F.Mask" "F.Paste")
			(net "TP_CHD_CPU0_DIMM1_FRU_5")
		)
		(pad "232" smd rect
			(at 2.050034 15.724886 270)
			(size 0.519938 1.4986)
			(layers "F.Cu" "F.Mask" "F.Paste")
			(net "TP_CHD_CPU0_DIMM1_FRU_6")
		)
		(pad "233" smd rect
			(at 2.050034 16.575024 270)
			(size 0.519938 1.4986)
			(layers "F.Cu" "F.Mask" "F.Paste")
			(net "GND")
		)
		(pad "234" smd rect
			(at 2.050034 17.424908 270)
			(size 0.519938 1.4986)
			(layers "F.Cu" "F.Mask" "F.Paste")
			(net "M_D_CPU0_SB_CB<6>")
		)
		(pad "235" smd rect
			(at 2.050034 18.275046 270)
			(size 0.519938 1.4986)
			(layers "F.Cu" "F.Mask" "F.Paste")
			(net "GND")
		)
		(pad "236" smd rect
			(at 2.050034 19.12493 270)
			(size 0.519938 1.4986)
			(layers "F.Cu" "F.Mask" "F.Paste")
			(net "M_D_CPU0_SB_CB<7>")
		)
		(pad "237" smd rect
			(at 2.050034 19.975068 270)
			(size 0.519938 1.4986)
			(layers "F.Cu" "F.Mask" "F.Paste")
			(net "GND")
		)
		(pad "238" smd rect
			(at 2.050034 20.824952 270)
			(size 0.519938 1.4986)
			(layers "F.Cu" "F.Mask" "F.Paste")
			(net "M_D_CPU0_SB_DQS_DN<4>")
		)
		(pad "239" smd rect
			(at 2.050034 21.67509 270)
			(size 0.519938 1.4986)
			(layers "F.Cu" "F.Mask" "F.Paste")
			(net "M_D_CPU0_SB_DQS_DP<4>")
		)
		(pad "240" smd rect
			(at 2.050034 22.524974 270)
			(size 0.519938 1.4986)
			(layers "F.Cu" "F.Mask" "F.Paste")
			(net "GND")
		)
		(pad "241" smd rect
			(at 2.050034 23.375112 270)
			(size 0.519938 1.4986)
			(layers "F.Cu" "F.Mask" "F.Paste")
			(net "M_D_CPU0_SB_CB<2>")
		)
		(pad "242" smd rect
			(at 2.050034 24.224996 270)
			(size 0.519938 1.4986)
			(layers "F.Cu" "F.Mask" "F.Paste")
			(net "GND")
		)
		(pad "243" smd rect
			(at 2.050034 25.07488 270)
			(size 0.519938 1.4986)
			(layers "F.Cu" "F.Mask" "F.Paste")
			(net "M_D_CPU0_SB_CB<3>")
		)
		(pad "244" smd rect
			(at 2.050034 25.925018 270)
			(size 0.519938 1.4986)
			(layers "F.Cu" "F.Mask" "F.Paste")
			(net "GND")
		)
		(pad "245" smd rect
			(at 2.050034 26.774902 270)
			(size 0.519938 1.4986)
			(layers "F.Cu" "F.Mask" "F.Paste")
			(net "M_D_CPU0_SB_DQ<2>")
		)
		(pad "246" smd rect
			(at 2.050034 27.62504 270)
			(size 0.519938 1.4986)
			(layers "F.Cu" "F.Mask" "F.Paste")
			(net "GND")
		)
		(pad "247" smd rect
			(at 2.050034 28.474924 270)
			(size 0.519938 1.4986)
			(layers "F.Cu" "F.Mask" "F.Paste")
			(net "M_D_CPU0_SB_DQ<3>")
		)
		(pad "248" smd rect
			(at 2.050034 29.325062 270)
			(size 0.519938 1.4986)
			(layers "F.Cu" "F.Mask" "F.Paste")
			(net "GND")
		)
		(pad "249" smd rect
			(at 2.050034 30.174946 270)
			(size 0.519938 1.4986)
			(layers "F.Cu" "F.Mask" "F.Paste")
			(net "M_D_CPU0_SB_DQS_DN<5>")
		)
		(pad "250" smd rect
			(at 2.050034 31.025084 270)
			(size 0.519938 1.4986)
			(layers "F.Cu" "F.Mask" "F.Paste")
			(net "M_D_CPU0_SB_DQS_DP<5>")
		)
		(pad "251" smd rect
			(at 2.050034 31.874968 270)
			(size 0.519938 1.4986)
			(layers "F.Cu" "F.Mask" "F.Paste")
			(net "GND")
		)
		(pad "252" smd rect
			(at 2.050034 32.725106 270)
			(size 0.519938 1.4986)
			(layers "F.Cu" "F.Mask" "F.Paste")
			(net "M_D_CPU0_SB_DQ<6>")
		)
		(pad "253" smd rect
			(at 2.050034 33.57499 270)
			(size 0.519938 1.4986)
			(layers "F.Cu" "F.Mask" "F.Paste")
			(net "GND")
		)
		(pad "254" smd rect
			(at 2.050034 34.425128 270)
			(size 0.519938 1.4986)
			(layers "F.Cu" "F.Mask" "F.Paste")
			(net "M_D_CPU0_SB_DQ<7>")
		)
		(pad "255" smd rect
			(at 2.050034 35.275012 270)
			(size 0.519938 1.4986)
			(layers "F.Cu" "F.Mask" "F.Paste")
			(net "GND")
		)
		(pad "256" smd rect
			(at 2.050034 36.124896 270)
			(size 0.519938 1.4986)
			(layers "F.Cu" "F.Mask" "F.Paste")
			(net "M_D_CPU0_SB_DQ<10>")
		)
		(pad "257" smd rect
			(at 2.050034 36.975034 270)
			(size 0.519938 1.4986)
			(layers "F.Cu" "F.Mask" "F.Paste")
			(net "GND")
		)
		(pad "258" smd rect
			(at 2.050034 37.824918 270)
			(size 0.519938 1.4986)
			(layers "F.Cu" "F.Mask" "F.Paste")
			(net "M_D_CPU0_SB_DQ<11>")
		)
		(pad "259" smd rect
			(at 2.050034 38.675056 270)
			(size 0.519938 1.4986)
			(layers "F.Cu" "F.Mask" "F.Paste")
			(net "GND")
		)
		(pad "260" smd rect
			(at 2.050034 39.52494 270)
			(size 0.519938 1.4986)
			(layers "F.Cu" "F.Mask" "F.Paste")
			(net "M_D_CPU0_SB_DQS_DN<6>")
		)
		(pad "261" smd rect
			(at 2.050034 40.375078 270)
			(size 0.519938 1.4986)
			(layers "F.Cu" "F.Mask" "F.Paste")
			(net "M_D_CPU0_SB_DQS_DP<6>")
		)
		(pad "262" smd rect
			(at 2.050034 41.224962 270)
			(size 0.519938 1.4986)
			(layers "F.Cu" "F.Mask" "F.Paste")
			(net "GND")
		)
		(pad "263" smd rect
			(at 2.050034 42.0751 270)
			(size 0.519938 1.4986)
			(layers "F.Cu" "F.Mask" "F.Paste")
			(net "M_D_CPU0_SB_DQ<14>")
		)
		(pad "264" smd rect
			(at 2.050034 42.924984 270)
			(size 0.519938 1.4986)
			(layers "F.Cu" "F.Mask" "F.Paste")
			(net "GND")
		)
		(pad "265" smd rect
			(at 2.050034 43.775122 270)
			(size 0.519938 1.4986)
			(layers "F.Cu" "F.Mask" "F.Paste")
			(net "M_D_CPU0_SB_DQ<15>")
		)
		(pad "266" smd rect
			(at 2.050034 44.625006 270)
			(size 0.519938 1.4986)
			(layers "F.Cu" "F.Mask" "F.Paste")
			(net "GND")
		)
		(pad "267" smd rect
			(at 2.050034 45.47489 270)
			(size 0.519938 1.4986)
			(layers "F.Cu" "F.Mask" "F.Paste")
			(net "M_D_CPU0_SB_DQ<18>")
		)
		(pad "268" smd rect
			(at 2.050034 46.325028 270)
			(size 0.519938 1.4986)
			(layers "F.Cu" "F.Mask" "F.Paste")
			(net "GND")
		)
		(pad "269" smd rect
			(at 2.050034 47.174912 270)
			(size 0.519938 1.4986)
			(layers "F.Cu" "F.Mask" "F.Paste")
			(net "M_D_CPU0_SB_DQ<19>")
		)
		(pad "270" smd rect
			(at 2.050034 48.02505 270)
			(size 0.519938 1.4986)
			(layers "F.Cu" "F.Mask" "F.Paste")
			(net "GND")
		)
		(pad "271" smd rect
			(at 2.050034 48.874934 270)
			(size 0.519938 1.4986)
			(layers "F.Cu" "F.Mask" "F.Paste")
			(net "M_D_CPU0_SB_DQS_DN<7>")
		)
		(pad "272" smd rect
			(at 2.050034 49.725072 270)
			(size 0.519938 1.4986)
			(layers "F.Cu" "F.Mask" "F.Paste")
			(net "M_D_CPU0_SB_DQS_DP<7>")
		)
		(pad "273" smd rect
			(at 2.050034 50.574956 270)
			(size 0.519938 1.4986)
			(layers "F.Cu" "F.Mask" "F.Paste")
			(net "GND")
		)
		(pad "274" smd rect
			(at 2.050034 51.425094 270)
			(size 0.519938 1.4986)
			(layers "F.Cu" "F.Mask" "F.Paste")
			(net "M_D_CPU0_SB_DQ<22>")
		)
		(pad "275" smd rect
			(at 2.050034 52.274978 270)
			(size 0.519938 1.4986)
			(layers "F.Cu" "F.Mask" "F.Paste")
			(net "GND")
		)
		(pad "276" smd rect
			(at 2.050034 53.125116 270)
			(size 0.519938 1.4986)
			(layers "F.Cu" "F.Mask" "F.Paste")
			(net "M_D_CPU0_SB_DQ<23>")
		)
		(pad "277" smd rect
			(at 2.050034 53.975 270)
			(size 0.519938 1.4986)
			(layers "F.Cu" "F.Mask" "F.Paste")
			(net "GND")
		)
		(pad "278" smd rect
			(at 2.050034 54.824884 270)
			(size 0.519938 1.4986)
			(layers "F.Cu" "F.Mask" "F.Paste")
			(net "M_D_CPU0_SB_DQ<26>")
		)
		(pad "279" smd rect
			(at 2.050034 55.675022 270)
			(size 0.519938 1.4986)
			(layers "F.Cu" "F.Mask" "F.Paste")
			(net "GND")
		)
		(pad "280" smd rect
			(at 2.050034 56.524906 270)
			(size 0.519938 1.4986)
			(layers "F.Cu" "F.Mask" "F.Paste")
			(net "M_D_CPU0_SB_DQ<27>")
		)
		(pad "281" smd rect
			(at 2.050034 57.375044 270)
			(size 0.519938 1.4986)
			(layers "F.Cu" "F.Mask" "F.Paste")
			(net "GND")
		)
		(pad "282" smd rect
			(at 2.050034 58.224928 270)
			(size 0.519938 1.4986)
			(layers "F.Cu" "F.Mask" "F.Paste")
			(net "M_D_CPU0_SB_DQS_DN<8>")
		)
		(pad "283" smd rect
			(at 2.050034 59.075066 270)
			(size 0.519938 1.4986)
			(layers "F.Cu" "F.Mask" "F.Paste")
			(net "M_D_CPU0_SB_DQS_DP<8>")
		)
		(pad "284" smd rect
			(at 2.050034 59.92495 270)
			(size 0.519938 1.4986)
			(layers "F.Cu" "F.Mask" "F.Paste")
			(net "GND")
		)
		(pad "285" smd rect
			(at 2.050034 60.775088 270)
			(size 0.519938 1.4986)
			(layers "F.Cu" "F.Mask" "F.Paste")
			(net "M_D_CPU0_SB_DQ<30>")
		)
		(pad "286" smd rect
			(at 2.050034 61.624972 270)
			(size 0.519938 1.4986)
			(layers "F.Cu" "F.Mask" "F.Paste")
			(net "GND")
		)
		(pad "287" smd rect
			(at 2.050034 62.47511 270)
			(size 0.519938 1.4986)
			(layers "F.Cu" "F.Mask" "F.Paste")
			(net "M_D_CPU0_SB_DQ<31>")
		)
		(pad "288" smd rect
			(at 2.050034 63.324994 270)
			(size 0.519938 1.4986)
			(layers "F.Cu" "F.Mask" "F.Paste")
			(net "GND")
		)
		(pad "G1" thru_hole oval
			(at 0 -68.97497)
			(size 2.8194 1.5748)
			(drill oval 2.4384 1.1938)
			(layers "*.Cu" "*.Mask")
			(remove_unused_layers no)
			(net "GND")
			(clearance 0.127)
			(thermal_gap 0.127)
		)
		(pad "G2" thru_hole oval
			(at 0 3.875024)
			(size 2.8194 1.5748)
			(drill oval 2.4384 1.1938)
			(layers "*.Cu" "*.Mask")
			(remove_unused_layers no)
			(net "GND")
			(clearance 0.127)
			(thermal_gap 0.127)
		)
		(pad "G3" thru_hole oval
			(at 0 68.97497)
			(size 2.8194 1.5748)
			(drill oval 2.4384 1.1938)
			(layers "*.Cu" "*.Mask")
			(remove_unused_layers no)
			(net "GND")
			(clearance 0.127)
			(thermal_gap 0.127)
		)
	)
)
